# S9S_MB_2U (Grand Teton) — schematic netlist excerpt (pin names and nets, part order shuffled) for the footprints in the layout excerpt that follows; sources: Cadence DE-HDL packaged netlist, KiCad conversion of 03242023_DA0F0TMBIJ0_F0T_Motherboard_J_brd_V01_OCP.brd

U49  MOSFET_N  BSS138K IC  pkg SMLF  page 158
  DRAIN  = HP_LVC3_OCP_V3_1_PRSNT2
  GATE  = HP_LVC3_OCP_V3_1_PRSNT2_N
  SOURCE  = GND

R4175  Q_RES  33.2 1% CHIP  pkg 0402LF  page 215 : A = RST_PCIE_PCH_DEV_PERST_N ; B = RST_PCIE_PCH_DEV_PERST_M2_R_N
R3443  Q_RES  0 5% CHIP  pkg 0402LF  page 144 : A = GPU_PEX_STRAP1 ; B = GND

(kicad_pcb
	(version 20260206)
	(generator "pcbnew")
	(generator_version "10.0")
	(general
		(thickness 1.6)
		(legacy_teardrops no)
	)
	(paper "A4")
	(title_block
		(title "03242023_DA0F0TMBIJ0_F0T_Motherboard_J_brd_V01_OCP.brd")
		(comment 1 "Grand Teton / footprints 38-40 of 6105")
	)
	(layers
		(0 "F.Cu" signal "TOP")
		(4 "In1.Cu" signal "GND")
		(6 "In2.Cu" signal "IN1")
		(8 "In3.Cu" signal "GND1")
		(10 "In4.Cu" signal "IN2")
		(12 "In5.Cu" signal "GND2")
		(14 "In6.Cu" signal "IN3")
		(16 "In7.Cu" signal "GND3")
		(18 "In8.Cu" signal "VCC")
		(20 "In9.Cu" signal "VCC1")
		(22 "In10.Cu" signal "GND4")
		(24 "In11.Cu" signal "IN4")
		(26 "In12.Cu" signal "GND5")
		(28 "In13.Cu" signal "IN5")
		(30 "In14.Cu" signal "GND6")
		(32 "In15.Cu" signal "IN6")
		(34 "In16.Cu" signal "GND7")
		(2 "B.Cu" signal "BOTTOM")
		(9 "F.Adhes" user "F.Adhesive")
		(11 "B.Adhes" user "B.Adhesive")
		(13 "F.Paste" user "Package Geometry/Pastemask Top")
		(15 "B.Paste" user "Package Geometry/Pastemask Bottom")
		(5 "F.SilkS" user "Ref Des/Silkscreen Top")
		(7 "B.SilkS" user "Ref Des/Silkscreen Bottom")
		(1 "F.Mask" user "Board Geometry/Soldermask Top")
		(3 "B.Mask" user "Board Geometry/Soldermask Bottom")
		(17 "Dwgs.User" user "User.Drawings")
		(19 "Cmts.User" user "User.Comments")
		(21 "Eco1.User" user "User.Eco1")
		(23 "Eco2.User" user "User.Eco2")
		(25 "Edge.Cuts" user "Board Geometry/Outline")
		(27 "Margin" user)
		(31 "F.CrtYd" user "Package Geometry/Place Bound Top")
		(29 "B.CrtYd" user "Package Geometry/Place Bound Bottom")
		(35 "F.Fab" user "Ref Des/Assembly Top")
		(33 "B.Fab" user "Ref Des/Assembly Bottom")
	)
	(footprint ""
		(layer "F.Cu")
		(at 204.93736 -119.344948)
		(property "Reference" "R4175"
			(at 0 0 0)
			(layer "F.SilkS")
			(hide yes)
			(effects
				(font
					(size 1.27 1.27)
				)
			)
		)
		(property "Value" ""
			(at 0 0 0)
			(layer "F.Fab")
			(effects
				(font
					(size 1.27 1.27)
				)
			)
		)
		(duplicate_pad_numbers_are_jumpers no)
		(fp_line
			(start -0.7874 -0.4064)
			(end 0.7874 -0.4064)
			(stroke
				(width 0.1524)
				(type default)
			)
			(layer "F.SilkS")
		)
		(fp_line
			(start -0.7874 0.4064)
			(end -0.7874 -0.4064)
			(stroke
				(width 0.1524)
				(type default)
			)
			(layer "F.SilkS")
		)
		(fp_line
			(start 0.7874 -0.4064)
			(end 0.7874 0.4064)
			(stroke
				(width 0.1524)
				(type default)
			)
			(layer "F.SilkS")
		)
		(fp_line
			(start 0.7874 0.4064)
			(end -0.7874 0.4064)
			(stroke
				(width 0.1524)
				(type default)
			)
			(layer "F.SilkS")
		)
		(fp_line
			(start -0.67945 -0.305054)
			(end -0.12065 -0.305054)
			(stroke
				(width 0.1)
				(type default)
			)
			(layer "F.Fab")
		)
		(fp_line
			(start -0.67945 0.3048)
			(end -0.67945 -0.305054)
			(stroke
				(width 0.1)
				(type default)
			)
			(layer "F.Fab")
		)
		(fp_line
			(start -0.12065 -0.305054)
			(end -0.12065 -0.2794)
			(stroke
				(width 0.1)
				(type default)
			)
			(layer "F.Fab")
		)
		(fp_line
			(start -0.12065 -0.2794)
			(end 0.12065 -0.2794)
			(stroke
				(width 0.1)
				(type default)
			)
			(layer "F.Fab")
		)
		(fp_line
			(start -0.12065 0.2794)
			(end -0.12065 0.3048)
			(stroke
				(width 0.1)
				(type default)
			)
			(layer "F.Fab")
		)
		(fp_line
			(start -0.12065 0.3048)
			(end -0.67945 0.3048)
			(stroke
				(width 0.1)
				(type default)
			)
			(layer "F.Fab")
		)
		(fp_line
			(start 0.120396 0.2794)
			(end -0.12065 0.2794)
			(stroke
				(width 0.1)
				(type default)
			)
			(layer "F.Fab")
		)
		(fp_line
			(start 0.120396 0.3048)
			(end 0.120396 0.2794)
			(stroke
				(width 0.1)
				(type default)
			)
			(layer "F.Fab")
		)
		(fp_line
			(start 0.12065 -0.3048)
			(end 0.67945 -0.3048)
			(stroke
				(width 0.1)
				(type default)
			)
			(layer "F.Fab")
		)
		(fp_line
			(start 0.12065 -0.2794)
			(end 0.12065 -0.3048)
			(stroke
				(width 0.1)
				(type default)
			)
			(layer "F.Fab")
		)
		(fp_line
			(start 0.67945 -0.3048)
			(end 0.67945 0.3048)
			(stroke
				(width 0.1)
				(type default)
			)
			(layer "F.Fab")
		)
		(fp_line
			(start 0.67945 0.3048)
			(end 0.120396 0.3048)
			(stroke
				(width 0.1)
				(type default)
			)
			(layer "F.Fab")
		)
		(pad "1" smd circle
			(at -0.40005 0)
			(size 0 0)
			(layers "F.Cu" "F.Mask" "F.Paste")
			(net "RST_PCIE_PCH_DEV_PERST_N")
		)
		(pad "2" smd circle
			(at 0.40005 0)
			(size 0 0)
			(layers "F.Cu" "F.Mask" "F.Paste")
			(net "RST_PCIE_PCH_DEV_PERST_M2_R_N")
		)
	)
	(footprint ""
		(layer "F.Cu")
		(at 17.737582 -428.024036 90)
		(property "Reference" "R3443"
			(at 0 0 90)
			(layer "F.SilkS")
			(hide yes)
			(effects
				(font
					(size 1.27 1.27)
				)
			)
		)
		(property "Value" ""
			(at 0 0 90)
			(layer "F.Fab")
			(effects
				(font
					(size 1.27 1.27)
				)
			)
		)
		(duplicate_pad_numbers_are_jumpers no)
		(fp_line
			(start 0.7874 -0.4064)
			(end 0.7874 0.4064)
			(stroke
				(width 0.1524)
				(type default)
			)
			(layer "F.SilkS")
		)
		(fp_line
			(start -0.7874 -0.4064)
			(end 0.7874 -0.4064)
			(stroke
				(width 0.1524)
				(type default)
			)
			(layer "F.SilkS")
		)
		(fp_line
			(start 0.7874 0.4064)
			(end -0.7874 0.4064)
			(stroke
				(width 0.1524)
				(type default)
			)
			(layer "F.SilkS")
		)
		(fp_line
			(start -0.7874 0.4064)
			(end -0.7874 -0.4064)
			(stroke
				(width 0.1524)
				(type default)
			)
			(layer "F.SilkS")
		)
		(fp_line
			(start -0.12065 -0.305054)
			(end -0.12065 -0.2794)
			(stroke
				(width 0.1)
				(type default)
			)
			(layer "F.Fab")
		)
		(fp_line
			(start -0.67945 -0.305054)
			(end -0.12065 -0.305054)
			(stroke
				(width 0.1)
				(type default)
			)
			(layer "F.Fab")
		)
		(fp_line
			(start 0.67945 -0.3048)
			(end 0.67945 0.3048)
			(stroke
				(width 0.1)
				(type default)
			)
			(layer "F.Fab")
		)
		(fp_line
			(start 0.12065 -0.3048)
			(end 0.67945 -0.3048)
			(stroke
				(width 0.1)
				(type default)
			)
			(layer "F.Fab")
		)
		(fp_line
			(start 0.12065 -0.2794)
			(end 0.12065 -0.3048)
			(stroke
				(width 0.1)
				(type default)
			)
			(layer "F.Fab")
		)
		(fp_line
			(start -0.12065 -0.2794)
			(end 0.12065 -0.2794)
			(stroke
				(width 0.1)
				(type default)
			)
			(layer "F.Fab")
		)
		(fp_line
			(start 0.120396 0.2794)
			(end -0.12065 0.2794)
			(stroke
				(width 0.1)
				(type default)
			)
			(layer "F.Fab")
		)
		(fp_line
			(start -0.12065 0.2794)
			(end -0.12065 0.3048)
			(stroke
				(width 0.1)
				(type default)
			)
			(layer "F.Fab")
		)
		(fp_line
			(start 0.67945 0.3048)
			(end 0.120396 0.3048)
			(stroke
				(width 0.1)
				(type default)
			)
			(layer "F.Fab")
		)
		(fp_line
			(start 0.120396 0.3048)
			(end 0.120396 0.2794)
			(stroke
				(width 0.1)
				(type default)
			)
			(layer "F.Fab")
		)
		(fp_line
			(start -0.12065 0.3048)
			(end -0.67945 0.3048)
			(stroke
				(width 0.1)
				(type default)
			)
			(layer "F.Fab")
		)
		(fp_line
			(start -0.67945 0.3048)
			(end -0.67945 -0.305054)
			(stroke
				(width 0.1)
				(type default)
			)
			(layer "F.Fab")
		)
		(pad "1" smd circle
			(at -0.40005 0 90)
			(size 0 0)
			(layers "F.Cu" "F.Mask" "F.Paste")
			(net "GPU_PEX_STRAP1")
		)
		(pad "2" smd circle
			(at 0.40005 0 90)
			(size 0 0)
			(layers "F.Cu" "F.Mask" "F.Paste")
			(net "GND")
		)
	)
	(footprint ""
		(layer "F.Cu")
		(at 450.558154 -110.183422 180)
		(property "Reference" "U49"
			(at 1.041908 -2.61874 0)
			(unlocked yes)
			(layer "F.SilkS")
			(effects
				(font
					(size 0.7874 0.5842)
					(thickness 0.1524)
				)
			)
		)
		(property "Value" ""
			(at 0 0 180)
			(layer "F.Fab")
			(effects
				(font
					(size 1.27 1.27)
				)
			)
		)
		(duplicate_pad_numbers_are_jumpers no)
		(fp_line
			(start 1.949958 1.610106)
			(end -1.949958 1.610106)
			(stroke
				(width 0.1524)
				(type default)
			)
			(layer "F.SilkS")
		)
		(fp_line
			(start 1.949958 -1.560068)
			(end 1.949958 1.610106)
			(stroke
				(width 0.1524)
				(type default)
			)
			(layer "F.SilkS")
		)
		(fp_line
			(start -1.949958 1.610106)
			(end -1.949958 -1.610106)
			(stroke
				(width 0.1524)
				(type default)
			)
			(layer "F.SilkS")
		)
		(fp_line
			(start -1.949958 -1.610106)
			(end 1.949958 -1.610106)
			(stroke
				(width 0.1524)
				(type default)
			)
			(layer "F.SilkS")
		)
		(fp_line
			(start 0.750062 1.560068)
			(end -0.750062 1.560068)
			(stroke
				(width 0.1)
				(type default)
			)
			(layer "F.Fab")
		)
		(fp_line
			(start 0.750062 -1.560068)
			(end 0.750062 1.560068)
			(stroke
				(width 0.1)
				(type default)
			)
			(layer "F.Fab")
		)
		(fp_line
			(start -0.750062 1.560068)
			(end -0.750062 -1.560068)
			(stroke
				(width 0.1)
				(type default)
			)
			(layer "F.Fab")
		)
		(fp_line
			(start -0.750062 -1.560068)
			(end 0.750062 -1.560068)
			(stroke
				(width 0.1)
				(type default)
			)
			(layer "F.Fab")
		)
		(pad "D" smd rect
			(at 1.100074 0 90)
			(size 1.016 1.4224)
			(layers "F.Cu" "F.Mask" "F.Paste")
			(net "HP_LVC3_OCP_V3_1_PRSNT2")
		)
		(pad "G" smd rect
			(at -1.100074 -0.94996 90)
			(size 1.016 1.4224)
			(layers "F.Cu" "F.Mask" "F.Paste")
			(net "HP_LVC3_OCP_V3_1_PRSNT2_N")
		)
		(pad "S" smd rect
			(at -1.100074 0.94996 90)
			(size 1.016 1.4224)
			(layers "F.Cu" "F.Mask" "F.Paste")
			(net "GND")
		)
	)
)
